(kicad_pcb
	(version 20241229)
	(generator "pcbnew")
	(generator_version "9.0")
	(general
		(thickness 1.61)
		(legacy_teardrops no)
	)
	(paper "A3")
	(title_block
		(title "RDIMM DDR5 Tester")
		(date "2026-05-21")
		(rev "2.2.0")
		(company "Antmicro")
		(comment 9 "footprints 740-744 of 796")
	)
	(layers
		(0 "F.Cu" signal)
		(4 "In1.Cu" power)
		(6 "In2.Cu" mixed)
		(8 "In3.Cu" power)
		(10 "In4.Cu" mixed)
		(12 "In5.Cu" power)
		(14 "In6.Cu" mixed)
		(16 "In7.Cu" power)
		(18 "In8.Cu" power)
		(20 "In9.Cu" mixed)
		(22 "In10.Cu" power)
		(2 "B.Cu" signal)
		(9 "F.Adhes" user "F.Adhesive")
		(11 "B.Adhes" user "B.Adhesive")
		(13 "F.Paste" user)
		(15 "B.Paste" user)
		(5 "F.SilkS" user "F.Silkscreen")
		(7 "B.SilkS" user "B.Silkscreen")
		(1 "F.Mask" user)
		(3 "B.Mask" user)
		(17 "Dwgs.User" user "User.Drawings")
		(19 "Cmts.User" user "User.Comments")
		(21 "Eco1.User" user "User.Eco1")
		(23 "Eco2.User" user "User.Eco2")
		(25 "Edge.Cuts" user)
		(27 "Margin" user)
		(31 "F.CrtYd" user "F.Courtyard")
		(29 "B.CrtYd" user "B.Courtyard")
		(35 "F.Fab" user)
		(33 "B.Fab" user)
	)
	(footprint "antmicro-footprints:C_0402_1005Metric"
		(layer "B.Cu")
		(at 124.2 162.5 180)
		(descr "Capacitor SMD 0402")
		(tags "capacitor SMD 0402")
		(property "Reference" "C297"
			(at -4.05 -0.35 0)
			(layer "B.SilkS")
			(effects
				(font
					(size 0.7 0.7)
					(thickness 0.15)
				)
				(justify left bottom mirror)
			)
		)
		(property "Value" "C_100n_0402"
			(at -1.022927 -2.155213 0)
			(layer "B.Fab")
			(effects
				(font
					(size 0.7 0.7)
					(thickness 0.15)
				)
				(justify left bottom mirror)
			)
		)
		(property "Datasheet" "https://www.murata.com/products/productdetail?partno=GRM155R61H104KE14%23"
			(at 0 0 180)
			(layer "F.Fab")
			(hide yes)
			(effects
				(font
					(size 1.27 1.27)
					(thickness 0.15)
				)
			)
		)
		(property "MPN" "GRM155R61H104KE14D"
			(at 0 0 180)
			(unlocked yes)
			(layer "B.Fab")
			(hide yes)
			(effects
				(font
					(size 1 1)
					(thickness 0.15)
				)
				(justify mirror)
			)
		)
		(property "Manufacturer" "Murata"
			(at 0 0 180)
			(unlocked yes)
			(layer "B.Fab")
			(hide yes)
			(effects
				(font
					(size 1 1)
					(thickness 0.15)
				)
				(justify mirror)
			)
		)
		(property "License" "Apache-2.0"
			(at 0 0 180)
			(unlocked yes)
			(layer "B.Fab")
			(hide yes)
			(effects
				(font
					(size 1 1)
					(thickness 0.15)
				)
				(justify mirror)
			)
		)
		(property "Author" "Antmicro"
			(at 0 0 180)
			(unlocked yes)
			(layer "B.Fab")
			(hide yes)
			(effects
				(font
					(size 1 1)
					(thickness 0.15)
				)
				(justify mirror)
			)
		)
		(property "Val" "100n"
			(at 0 0 180)
			(unlocked yes)
			(layer "B.Fab")
			(hide yes)
			(effects
				(font
					(size 1 1)
					(thickness 0.15)
				)
				(justify mirror)
			)
		)
		(property "Voltage" "50V"
			(at 0 0 180)
			(unlocked yes)
			(layer "B.Fab")
			(hide yes)
			(effects
				(font
					(size 1 1)
					(thickness 0.15)
				)
				(justify mirror)
			)
		)
		(property "Dielectric" "X5R"
			(at 0 0 180)
			(unlocked yes)
			(layer "B.Fab")
			(hide yes)
			(effects
				(font
					(size 1 1)
					(thickness 0.15)
				)
				(justify mirror)
			)
		)
		(sheetname "/HDMI + SD Card/")
		(sheetfile "hdmi-sd-card.kicad_sch")
		(attr smd)
		(fp_rect
			(start -0.925 0.47)
			(end 0.925 -0.47)
			(stroke
				(width 0.05)
				(type default)
			)
			(fill no)
			(layer "B.CrtYd")
		)
		(fp_line
			(start 0.504 0.25)
			(end 0.504 -0.248)
			(stroke
				(width 0.15)
				(type solid)
			)
			(layer "B.Fab")
		)
		(fp_line
			(start 0.504 -0.248)
			(end -0.494 -0.248)
			(stroke
				(width 0.15)
				(type solid)
			)
			(layer "B.Fab")
		)
		(fp_line
			(start -0.494 0.25)
			(end 0.504 0.25)
			(stroke
				(width 0.15)
				(type solid)
			)
			(layer "B.Fab")
		)
		(fp_line
			(start -0.494 -0.248)
			(end -0.494 0.25)
			(stroke
				(width 0.15)
				(type solid)
			)
			(layer "B.Fab")
		)
		(fp_text user "${REFERENCE}"
			(at -0.939 -4.599 0)
			(layer "B.Fab")
			(effects
				(font
					(size 0.7 0.7)
					(thickness 0.15)
				)
				(justify left bottom mirror)
			)
		)
		(fp_text user "Author: Antmicro"
			(at -0.939 -3.399 0)
			(layer "B.Fab")
			(effects
				(font
					(size 0.7 0.7)
					(thickness 0.15)
				)
				(justify left bottom mirror)
			)
		)
		(fp_text user "License: Apache-2.0"
			(at -0.939 -5.799 0)
			(layer "B.Fab")
			(effects
				(font
					(size 0.7 0.7)
					(thickness 0.15)
				)
				(justify left bottom mirror)
			)
		)
		(pad "1" smd roundrect
			(at -0.48 0 180)
			(size 0.59 0.64)
			(layers "B.Cu" "B.Mask" "B.Paste")
			(roundrect_rratio 0.25)
			(net 1 "GND")
			(pintype "passive")
		)
		(pad "2" smd roundrect
			(at 0.48 0 180)
			(size 0.59 0.64)
			(layers "B.Cu" "B.Mask" "B.Paste")
			(roundrect_rratio 0.25)
			(net 151 "+3V3")
			(pintype "passive")
		)
	)
	(footprint "antmicro-footprints:C_0402_1005Metric_EIA"
		(layer "B.Cu")
		(at 191 148.5 -90)
		(descr "Capacitor SMD 0402 (1005 Metric), square (rectangular) end terminal, IPC_7351 nominal, (Body size source: IPC-SM-782 page 76, https://www.pcb-3d.com/wordpress/wp-content/uploads/ipc-sm-782a_amendment_1_and_2.pdf)")
		(tags "capacitor 0402")
		(property "Reference" "C65"
			(at -12.125 30.675 90)
			(layer "B.SilkS")
			(effects
				(font
					(size 0.7 0.7)
					(thickness 0.15)
				)
				(justify left bottom mirror)
			)
		)
		(property "Value" "C_100n_0402"
			(at 0 -1.169 90)
			(layer "B.Fab")
			(effects
				(font
					(size 0.7 0.7)
					(thickness 0.15)
				)
				(justify left bottom mirror)
			)
		)
		(property "Datasheet" "https://www.murata.com/products/productdetail?partno=GRM155R61H104KE14%23"
			(at 0 0 270)
			(layer "F.Fab")
			(hide yes)
			(effects
				(font
					(size 1.27 1.27)
					(thickness 0.15)
				)
			)
		)
		(property "MPN" "GRM155R61H104KE14D"
			(at 0 0 270)
			(unlocked yes)
			(layer "B.Fab")
			(hide yes)
			(effects
				(font
					(size 1 1)
					(thickness 0.15)
				)
				(justify mirror)
			)
		)
		(property "Manufacturer" "Murata"
			(at 0 0 270)
			(unlocked yes)
			(layer "B.Fab")
			(hide yes)
			(effects
				(font
					(size 1 1)
					(thickness 0.15)
				)
				(justify mirror)
			)
		)
		(property "License" "Apache-2.0"
			(at 0 0 270)
			(unlocked yes)
			(layer "B.Fab")
			(hide yes)
			(effects
				(font
					(size 1 1)
					(thickness 0.15)
				)
				(justify mirror)
			)
		)
		(property "Author" "Antmicro"
			(at 0 0 270)
			(unlocked yes)
			(layer "B.Fab")
			(hide yes)
			(effects
				(font
					(size 1 1)
					(thickness 0.15)
				)
				(justify mirror)
			)
		)
		(property "Val" "100n"
			(at 0 0 270)
			(unlocked yes)
			(layer "B.Fab")
			(hide yes)
			(effects
				(font
					(size 1 1)
					(thickness 0.15)
				)
				(justify mirror)
			)
		)
		(property "Voltage" "50V"
			(at 0 0 270)
			(unlocked yes)
			(layer "B.Fab")
			(hide yes)
			(effects
				(font
					(size 1 1)
					(thickness 0.15)
				)
				(justify mirror)
			)
		)
		(property "Dielectric" "X5R"
			(at 0 0 270)
			(unlocked yes)
			(layer "B.Fab")
			(hide yes)
			(effects
				(font
					(size 1 1)
					(thickness 0.15)
				)
				(justify mirror)
			)
		)
		(sheetname "/FPGA power/")
		(sheetfile "fpga-power.kicad_sch")
		(attr smd)
		(fp_rect
			(start -0.95 0.45)
			(end 0.95 -0.45)
			(stroke
				(width 0.05)
				(type default)
			)
			(fill no)
			(layer "B.CrtYd")
		)
		(fp_line
			(start -0.5 0.25)
			(end 0.498 0.25)
			(stroke
				(width 0.15)
				(type solid)
			)
			(layer "B.Fab")
		)
		(fp_line
			(start 0.498 0.25)
			(end 0.498 -0.248)
			(stroke
				(width 0.15)
				(type solid)
			)
			(layer "B.Fab")
		)
		(fp_line
			(start -0.5 -0.248)
			(end -0.5 0.25)
			(stroke
				(width 0.15)
				(type solid)
			)
			(layer "B.Fab")
		)
		(fp_line
			(start 0.498 -0.248)
			(end -0.5 -0.248)
			(stroke
				(width 0.15)
				(type solid)
			)
			(layer "B.Fab")
		)
		(fp_text user "License: Apache-2.0"
			(at -0.9656 -4.369 90)
			(layer "B.Fab")
			(effects
				(font
					(size 0.7 0.7)
					(thickness 0.15)
				)
				(justify left bottom mirror)
			)
		)
		(fp_text user "${REFERENCE}"
			(at -0.9656 -3.169 90)
			(layer "B.Fab")
			(effects
				(font
					(size 0.7 0.7)
					(thickness 0.15)
				)
				(justify left bottom mirror)
			)
		)
		(fp_text user "Author: Antmicro"
			(at -0.9656 -5.569 90)
			(layer "B.Fab")
			(effects
				(font
					(size 0.7 0.7)
					(thickness 0.15)
				)
				(justify left bottom mirror)
			)
		)
		(pad "1" smd roundrect
			(at -0.5 0 180)
			(size 0.6 0.6)
			(layers "B.Cu" "B.Mask" "B.Paste")
			(roundrect_rratio 0.25)
			(net 1 "GND")
			(pintype "passive")
		)
		(pad "2" smd roundrect
			(at 0.498 0 270)
			(size 0.6 0.6)
			(layers "B.Cu" "B.Mask" "B.Paste")
			(roundrect_rratio 0.25)
			(net 553 "+0V85")
			(pintype "passive")
		)
	)
	(footprint "antmicro-footprints:Fiducial_1mm_Mask2mm"
		(layer "B.Cu")
		(at 259.37 102.04)
		(descr "Circular Fiducial, 1mm bare copper, 3mm soldermask opening")
		(tags "fiducial")
		(property "Reference" "FID1003"
			(at 0 1.4 0)
			(layer "B.SilkS")
			(hide yes)
			(effects
				(font
					(size 0.7 0.7)
					(thickness 0.15)
				)
				(justify right bottom mirror)
			)
		)
		(property "Value" "Fiducial_1mm_Mask2mm"
			(at 0 -2.2 0)
			(layer "B.Fab")
			(effects
				(font
					(size 0.7 0.7)
					(thickness 0.15)
				)
				(justify right bottom mirror)
			)
		)
		(sheetfile "data-center-rdimm-ddr5-tester.kicad_sch")
		(attr board_only exclude_from_pos_files exclude_from_bom)
		(fp_circle
			(center 0 0)
			(end 1.24 0)
			(stroke
				(width 0.05)
				(type solid)
			)
			(fill no)
			(layer "B.CrtYd")
		)
		(fp_circle
			(center 0 0)
			(end 0.999 0)
			(stroke
				(width 0.15)
				(type solid)
			)
			(fill no)
			(layer "B.Fab")
		)
		(fp_text user "${REFERENCE}"
			(at -1.25 -4.603 180)
			(layer "B.Fab")
			(effects
				(font
					(size 0.7 0.7)
					(thickness 0.15)
				)
				(justify left bottom mirror)
			)
		)
		(fp_text user "Author: Antmicro"
			(at -1.25 -5.803 180)
			(layer "B.Fab")
			(effects
				(font
					(size 0.7 0.7)
					(thickness 0.15)
				)
				(justify left bottom mirror)
			)
		)
		(fp_text user "License: Apache-2.0"
			(at -1.25 -7.003 180)
			(layer "B.Fab")
			(effects
				(font
					(size 0.7 0.7)
					(thickness 0.15)
				)
				(justify left bottom mirror)
			)
		)
		(pad "" smd circle
			(at 0 0)
			(size 1 1)
			(layers "B.Cu" "B.Mask")
			(solder_mask_margin 0.5)
			(clearance 0.5)
		)
	)
	(footprint "antmicro-footprints:C_0805_2012Metric"
		(layer "B.Cu")
		(at 230.005 185.800001)
		(descr "Capacitor SMD 0805")
		(tags "capacitor SMD 0805")
		(property "Reference" "C200"
			(at 1.945 0.799999 0)
			(layer "B.SilkS")
			(effects
				(font
					(size 0.7 0.7)
					(thickness 0.15)
				)
				(justify right bottom mirror)
			)
		)
		(property "Value" "C_22u_25V_0805"
			(at -2.055717 -1.963152 0)
			(layer "B.Fab")
			(effects
				(font
					(size 0.7 0.7)
					(thickness 0.15)
				)
				(justify right bottom mirror)
			)
		)
		(property "Datasheet" "https://product.samsungsem.com/mlcc/CL21A226MAYNNN.do"
			(at 0 0 0)
			(layer "F.Fab")
			(hide yes)
			(effects
				(font
					(size 1.27 1.27)
					(thickness 0.15)
				)
			)
		)
		(property "MPN" "CL21A226MAYNNNE"
			(at 0 0 0)
			(unlocked yes)
			(layer "B.Fab")
			(hide yes)
			(effects
				(font
					(size 1 1)
					(thickness 0.15)
				)
				(justify mirror)
			)
		)
		(property "Manufacturer" "Samsung Electro-Mechanics"
			(at 0 0 0)
			(unlocked yes)
			(layer "B.Fab")
			(hide yes)
			(effects
				(font
					(size 1 1)
					(thickness 0.15)
				)
				(justify mirror)
			)
		)
		(property "License" "Apache-2.0"
			(at 0 0 0)
			(unlocked yes)
			(layer "B.Fab")
			(hide yes)
			(effects
				(font
					(size 1 1)
					(thickness 0.15)
				)
				(justify mirror)
			)
		)
		(property "Author" "Antmicro"
			(at 0 0 0)
			(unlocked yes)
			(layer "B.Fab")
			(hide yes)
			(effects
				(font
					(size 1 1)
					(thickness 0.15)
				)
				(justify mirror)
			)
		)
		(property "Val" "22u"
			(at 0 0 0)
			(unlocked yes)
			(layer "B.Fab")
			(hide yes)
			(effects
				(font
					(size 1 1)
					(thickness 0.15)
				)
				(justify mirror)
			)
		)
		(property "Voltage" "25V"
			(at 0 0 0)
			(unlocked yes)
			(layer "B.Fab")
			(hide yes)
			(effects
				(font
					(size 1 1)
					(thickness 0.15)
				)
				(justify mirror)
			)
		)
		(property "Dielectric" "X5R"
			(at 0 0 0)
			(unlocked yes)
			(layer "B.Fab")
			(hide yes)
			(effects
				(font
					(size 1 1)
					(thickness 0.15)
				)
				(justify mirror)
			)
		)
		(property "Public" "False"
			(at 0 0 0)
			(unlocked yes)
			(layer "B.Fab")
			(hide yes)
			(effects
				(font
					(size 1 1)
					(thickness 0.15)
				)
				(justify mirror)
			)
		)
		(sheetname "/Supply/DC-DC VCCINT/")
		(sheetfile "dc-dc-vccint.kicad_sch")
		(attr smd)
		(fp_line
			(start -0.3 -0.7)
			(end 0.3 -0.7)
			(stroke
				(width 0.15)
				(type solid)
			)
			(layer "B.SilkS")
		)
		(fp_line
			(start -0.3 0.7)
			(end 0.3 0.7)
			(stroke
				(width 0.15)
				(type solid)
			)
			(layer "B.SilkS")
		)
		(fp_rect
			(start 1.95 0.9)
			(end -1.95 -0.9)
			(stroke
				(width 0.05)
				(type default)
			)
			(fill no)
			(layer "B.CrtYd")
		)
		(fp_rect
			(start -0.95 0.675)
			(end 0.95 -0.675)
			(stroke
				(width 0.15)
				(type solid)
			)
			(fill no)
			(layer "B.Fab")
		)
		(fp_text user "License: Apache-2.0"
			(at -1.9 -4.947 180)
			(layer "B.Fab")
			(effects
				(font
					(size 0.7 0.7)
					(thickness 0.15)
				)
				(justify left bottom mirror)
			)
		)
		(fp_text user "Author: Antmicro"
			(at -1.9 -5.947 180)
			(layer "B.Fab")
			(effects
				(font
					(size 0.7 0.7)
					(thickness 0.15)
				)
				(justify left bottom mirror)
			)
		)
		(fp_text user "${REFERENCE}"
			(at -1.9 -3.947 180)
			(layer "B.Fab")
			(effects
				(font
					(size 0.7 0.7)
					(thickness 0.15)
				)
				(justify left bottom mirror)
			)
		)
		(pad "1" smd roundrect
			(at -1.1 0)
			(size 1.2 1.3)
			(layers "B.Cu" "B.Mask" "B.Paste")
			(roundrect_rratio 0.25)
			(net 1 "GND")
			(pintype "passive")
		)
		(pad "2" smd roundrect
			(at 1.1 0)
			(size 1.2 1.3)
			(layers "B.Cu" "B.Mask" "B.Paste")
			(roundrect_rratio 0.25)
			(net 35 "VDC")
			(pintype "passive")
		)
	)
	(footprint "antmicro-footprints:R_0402_1005Metric"
		(layer "B.Cu")
		(at 209.89 150.6095 180)
		(descr "Resistor SMD 0402")
		(tags "resistor SMD 0402")
		(property "Reference" "R6"
			(at -2.64 -0.5005 0)
			(layer "B.SilkS")
			(effects
				(font
					(size 0.7 0.7)
					(thickness 0.15)
				)
				(justify left bottom mirror)
			)
		)
		(property "Value" "R_22R_0402"
			(at -1.011843 -1.772047 0)
			(layer "B.Fab")
			(effects
				(font
					(size 0.7 0.7)
					(thickness 0.15)
				)
				(justify left bottom mirror)
			)
		)
		(property "Datasheet" "https://www.bourns.com/docs/product-datasheets/cr.pdf"
			(at 0 0 180)
			(layer "F.Fab")
			(hide yes)
			(effects
				(font
					(size 1.27 1.27)
					(thickness 0.15)
				)
			)
		)
		(property "Manufacturer" "Bourns"
			(at 0 0 180)
			(unlocked yes)
			(layer "B.Fab")
			(hide yes)
			(effects
				(font
					(size 1 1)
					(thickness 0.15)
				)
				(justify mirror)
			)
		)
		(property "MPN" "CR0402-FX-22R0GLF"
			(at 0 0 180)
			(unlocked yes)
			(layer "B.Fab")
			(hide yes)
			(effects
				(font
					(size 1 1)
					(thickness 0.15)
				)
				(justify mirror)
			)
		)
		(property "Val" "22R"
			(at 0 0 180)
			(unlocked yes)
			(layer "B.Fab")
			(hide yes)
			(effects
				(font
					(size 1 1)
					(thickness 0.15)
				)
				(justify mirror)
			)
		)
		(property "License" "Apache-2.0"
			(at 0 0 180)
			(unlocked yes)
			(layer "B.Fab")
			(hide yes)
			(effects
				(font
					(size 1 1)
					(thickness 0.15)
				)
				(justify mirror)
			)
		)
		(property "Author" "Antmicro"
			(at 0 0 180)
			(unlocked yes)
			(layer "B.Fab")
			(hide yes)
			(effects
				(font
					(size 1 1)
					(thickness 0.15)
				)
				(justify mirror)
			)
		)
		(property "Tolerance" "1%"
			(at 0 0 180)
			(unlocked yes)
			(layer "B.Fab")
			(hide yes)
			(effects
				(font
					(size 1 1)
					(thickness 0.15)
				)
				(justify mirror)
			)
		)
		(sheetname "/HyperRAM + QSPI Flash/")
		(sheetfile "hyperram-flash.kicad_sch")
		(attr smd)
		(fp_rect
			(start -0.925 0.47)
			(end 0.925 -0.47)
			(stroke
				(width 0.05)
				(type default)
			)
			(fill no)
			(layer "B.CrtYd")
		)
		(fp_rect
			(start -0.5 0.25)
			(end 0.5 -0.25)
			(stroke
				(width 0.15)
				(type solid)
			)
			(fill no)
			(layer "B.Fab")
		)
		(fp_text user "License: Apache-2.0"
			(at -0.95 -5.169 0)
			(layer "B.Fab")
			(effects
				(font
					(size 0.7 0.7)
					(thickness 0.15)
				)
				(justify left bottom mirror)
			)
		)
		(fp_text user "${REFERENCE}"
			(at -0.95 -3.168 0)
			(layer "B.Fab")
			(effects
				(font
					(size 0.7 0.7)
					(thickness 0.15)
				)
				(justify left bottom mirror)
			)
		)
		(fp_text user "Author: Antmicro"
			(at -0.95 -4.169 0)
			(layer "B.Fab")
			(effects
				(font
					(size 0.7 0.7)
					(thickness 0.15)
				)
				(justify left bottom mirror)
			)
		)
		(pad "1" smd roundrect
			(at -0.48 0 180)
			(size 0.59 0.64)
			(layers "B.Cu" "B.Mask" "B.Paste")
			(roundrect_rratio 0.25)
			(net 281 "/HyperRAM + QSPI Flash/IO0")
			(pintype "passive")
		)
		(pad "2" smd roundrect
			(at 0.48 0 180)
			(size 0.59 0.64)
			(layers "B.Cu" "B.Mask" "B.Paste")
			(roundrect_rratio 0.25)
			(net 351 "/FPGA Config/FLASH.IO0")
			(pintype "passive")
		)
	)
)
